(kicad_pcb
	(version 20260206)
	(generator "pcbnew")
	(generator_version "10.0")
	(general
		(thickness 1.6)
		(legacy_teardrops no)
	)
	(paper "A4")
	(title_block
		(title "03242023_DA0F0TMBIJ0_F0T_Motherboard_J_brd_V01_OCP.brd")
		(comment 1 "Grand Teton / footprints 4616-4622 of 6105")
	)
	(layers
		(0 "F.Cu" signal "TOP")
		(4 "In1.Cu" signal "GND")
		(6 "In2.Cu" signal "IN1")
		(8 "In3.Cu" signal "GND1")
		(10 "In4.Cu" signal "IN2")
		(12 "In5.Cu" signal "GND2")
		(14 "In6.Cu" signal "IN3")
		(16 "In7.Cu" signal "GND3")
		(18 "In8.Cu" signal "VCC")
		(20 "In9.Cu" signal "VCC1")
		(22 "In10.Cu" signal "GND4")
		(24 "In11.Cu" signal "IN4")
		(26 "In12.Cu" signal "GND5")
		(28 "In13.Cu" signal "IN5")
		(30 "In14.Cu" signal "GND6")
		(32 "In15.Cu" signal "IN6")
		(34 "In16.Cu" signal "GND7")
		(2 "B.Cu" signal "BOTTOM")
		(9 "F.Adhes" user "F.Adhesive")
		(11 "B.Adhes" user "B.Adhesive")
		(13 "F.Paste" user "Package Geometry/Pastemask Top")
		(15 "B.Paste" user "Package Geometry/Pastemask Bottom")
		(5 "F.SilkS" user "Ref Des/Silkscreen Top")
		(7 "B.SilkS" user "Ref Des/Silkscreen Bottom")
		(1 "F.Mask" user "Board Geometry/Soldermask Top")
		(3 "B.Mask" user "Board Geometry/Soldermask Bottom")
		(17 "Dwgs.User" user "User.Drawings")
		(19 "Cmts.User" user "User.Comments")
		(21 "Eco1.User" user "User.Eco1")
		(23 "Eco2.User" user "User.Eco2")
		(25 "Edge.Cuts" user "Board Geometry/Outline")
		(27 "Margin" user)
		(31 "F.CrtYd" user "Package Geometry/Place Bound Top")
		(29 "B.CrtYd" user "Package Geometry/Place Bound Bottom")
		(35 "F.Fab" user "Ref Des/Assembly Top")
		(33 "B.Fab" user "Ref Des/Assembly Bottom")
	)
	(footprint ""
		(layer "B.Cu")
		(at 180.367686 -423.631614)
		(property "Reference" "R2800"
			(at 0 0 0)
			(layer "B.SilkS")
			(hide yes)
			(effects
				(font
					(size 1.27 1.27)
				)
				(justify mirror)
			)
		)
		(property "Value" ""
			(at 0 0 0)
			(layer "B.Fab")
			(effects
				(font
					(size 1.27 1.27)
				)
				(justify mirror)
			)
		)
		(duplicate_pad_numbers_are_jumpers no)
		(fp_line
			(start -0.7874 -0.4064)
			(end -0.7874 0.4064)
			(stroke
				(width 0.1524)
				(type default)
			)
			(layer "B.SilkS")
		)
		(fp_line
			(start -0.7874 0.4064)
			(end 0.7874 0.4064)
			(stroke
				(width 0.1524)
				(type default)
			)
			(layer "B.SilkS")
		)
		(fp_line
			(start 0.7874 -0.4064)
			(end -0.7874 -0.4064)
			(stroke
				(width 0.1524)
				(type default)
			)
			(layer "B.SilkS")
		)
		(fp_line
			(start 0.7874 0.4064)
			(end 0.7874 -0.4064)
			(stroke
				(width 0.1524)
				(type default)
			)
			(layer "B.SilkS")
		)
		(fp_line
			(start -0.67945 -0.3048)
			(end -0.67945 0.3048)
			(stroke
				(width 0.1)
				(type default)
			)
			(layer "B.Fab")
		)
		(fp_line
			(start -0.67945 0.3048)
			(end -0.120396 0.3048)
			(stroke
				(width 0.1)
				(type default)
			)
			(layer "B.Fab")
		)
		(fp_line
			(start -0.12065 -0.3048)
			(end -0.67945 -0.3048)
			(stroke
				(width 0.1)
				(type default)
			)
			(layer "B.Fab")
		)
		(fp_line
			(start -0.12065 -0.2794)
			(end -0.12065 -0.3048)
			(stroke
				(width 0.1)
				(type default)
			)
			(layer "B.Fab")
		)
		(fp_line
			(start -0.120396 0.2794)
			(end 0.12065 0.2794)
			(stroke
				(width 0.1)
				(type default)
			)
			(layer "B.Fab")
		)
		(fp_line
			(start -0.120396 0.3048)
			(end -0.120396 0.2794)
			(stroke
				(width 0.1)
				(type default)
			)
			(layer "B.Fab")
		)
		(fp_line
			(start 0.12065 -0.305054)
			(end 0.12065 -0.2794)
			(stroke
				(width 0.1)
				(type default)
			)
			(layer "B.Fab")
		)
		(fp_line
			(start 0.12065 -0.2794)
			(end -0.12065 -0.2794)
			(stroke
				(width 0.1)
				(type default)
			)
			(layer "B.Fab")
		)
		(fp_line
			(start 0.12065 0.2794)
			(end 0.12065 0.3048)
			(stroke
				(width 0.1)
				(type default)
			)
			(layer "B.Fab")
		)
		(fp_line
			(start 0.12065 0.3048)
			(end 0.67945 0.3048)
			(stroke
				(width 0.1)
				(type default)
			)
			(layer "B.Fab")
		)
		(fp_line
			(start 0.67945 -0.305054)
			(end 0.12065 -0.305054)
			(stroke
				(width 0.1)
				(type default)
			)
			(layer "B.Fab")
		)
		(fp_line
			(start 0.67945 0.3048)
			(end 0.67945 -0.305054)
			(stroke
				(width 0.1)
				(type default)
			)
			(layer "B.Fab")
		)
		(pad "1" smd circle
			(at 0.40005 0 180)
			(size 0 0)
			(layers "B.Cu" "B.Mask" "B.Paste")
			(net "SMB_FAN_3V3AUX_R_SCL")
		)
		(pad "2" smd circle
			(at -0.40005 0 180)
			(size 0 0)
			(layers "B.Cu" "B.Mask" "B.Paste")
			(net "SMB_FAN_3V3AUX_BUF_SCL")
		)
	)
	(footprint ""
		(layer "B.Cu")
		(at 305.942238 -194.72021 90)
		(property "Reference" "R13"
			(at 0 0 90)
			(layer "B.SilkS")
			(hide yes)
			(effects
				(font
					(size 1.27 1.27)
				)
				(justify mirror)
			)
		)
		(property "Value" ""
			(at 0 0 90)
			(layer "B.Fab")
			(effects
				(font
					(size 1.27 1.27)
				)
				(justify mirror)
			)
		)
		(duplicate_pad_numbers_are_jumpers no)
		(fp_line
			(start 0.7874 -0.4064)
			(end -0.7874 -0.4064)
			(stroke
				(width 0.1524)
				(type default)
			)
			(layer "B.SilkS")
		)
		(fp_line
			(start -0.7874 -0.4064)
			(end -0.7874 0.4064)
			(stroke
				(width 0.1524)
				(type default)
			)
			(layer "B.SilkS")
		)
		(fp_line
			(start 0.7874 0.4064)
			(end 0.7874 -0.4064)
			(stroke
				(width 0.1524)
				(type default)
			)
			(layer "B.SilkS")
		)
		(fp_line
			(start -0.7874 0.4064)
			(end 0.7874 0.4064)
			(stroke
				(width 0.1524)
				(type default)
			)
			(layer "B.SilkS")
		)
		(fp_line
			(start 0.67945 -0.305054)
			(end 0.12065 -0.305054)
			(stroke
				(width 0.1)
				(type default)
			)
			(layer "B.Fab")
		)
		(fp_line
			(start 0.12065 -0.305054)
			(end 0.12065 -0.2794)
			(stroke
				(width 0.1)
				(type default)
			)
			(layer "B.Fab")
		)
		(fp_line
			(start -0.12065 -0.3048)
			(end -0.67945 -0.3048)
			(stroke
				(width 0.1)
				(type default)
			)
			(layer "B.Fab")
		)
		(fp_line
			(start -0.67945 -0.3048)
			(end -0.67945 0.3048)
			(stroke
				(width 0.1)
				(type default)
			)
			(layer "B.Fab")
		)
		(fp_line
			(start 0.12065 -0.2794)
			(end -0.12065 -0.2794)
			(stroke
				(width 0.1)
				(type default)
			)
			(layer "B.Fab")
		)
		(fp_line
			(start -0.12065 -0.2794)
			(end -0.12065 -0.3048)
			(stroke
				(width 0.1)
				(type default)
			)
			(layer "B.Fab")
		)
		(fp_line
			(start 0.12065 0.2794)
			(end 0.12065 0.3048)
			(stroke
				(width 0.1)
				(type default)
			)
			(layer "B.Fab")
		)
		(fp_line
			(start -0.120396 0.2794)
			(end 0.12065 0.2794)
			(stroke
				(width 0.1)
				(type default)
			)
			(layer "B.Fab")
		)
		(fp_line
			(start 0.67945 0.3048)
			(end 0.67945 -0.305054)
			(stroke
				(width 0.1)
				(type default)
			)
			(layer "B.Fab")
		)
		(fp_line
			(start 0.12065 0.3048)
			(end 0.67945 0.3048)
			(stroke
				(width 0.1)
				(type default)
			)
			(layer "B.Fab")
		)
		(fp_line
			(start -0.120396 0.3048)
			(end -0.120396 0.2794)
			(stroke
				(width 0.1)
				(type default)
			)
			(layer "B.Fab")
		)
		(fp_line
			(start -0.67945 0.3048)
			(end -0.120396 0.3048)
			(stroke
				(width 0.1)
				(type default)
			)
			(layer "B.Fab")
		)
		(pad "1" smd circle
			(at 0.40005 0 270)
			(size 0 0)
			(layers "B.Cu" "B.Mask" "B.Paste")
			(net "SVID_CLK0_CPU0")
		)
		(pad "2" smd circle
			(at -0.40005 0 270)
			(size 0 0)
			(layers "B.Cu" "B.Mask" "B.Paste")
			(net "SVID_CLK0_CPU0_R")
		)
	)
	(footprint ""
		(layer "B.Cu")
		(at 69.353684 -183.303926 90)
		(property "Reference" "R760"
			(at 0 0 90)
			(layer "B.SilkS")
			(hide yes)
			(effects
				(font
					(size 1.27 1.27)
				)
				(justify mirror)
			)
		)
		(property "Value" ""
			(at 0 0 90)
			(layer "B.Fab")
			(effects
				(font
					(size 1.27 1.27)
				)
				(justify mirror)
			)
		)
		(duplicate_pad_numbers_are_jumpers no)
		(fp_line
			(start 0.7874 -0.4064)
			(end -0.7874 -0.4064)
			(stroke
				(width 0.1524)
				(type default)
			)
			(layer "B.SilkS")
		)
		(fp_line
			(start -0.7874 -0.4064)
			(end -0.7874 0.4064)
			(stroke
				(width 0.1524)
				(type default)
			)
			(layer "B.SilkS")
		)
		(fp_line
			(start 0.7874 0.4064)
			(end 0.7874 -0.4064)
			(stroke
				(width 0.1524)
				(type default)
			)
			(layer "B.SilkS")
		)
		(fp_line
			(start -0.7874 0.4064)
			(end 0.7874 0.4064)
			(stroke
				(width 0.1524)
				(type default)
			)
			(layer "B.SilkS")
		)
		(fp_line
			(start 0.67945 -0.305054)
			(end 0.12065 -0.305054)
			(stroke
				(width 0.1)
				(type default)
			)
			(layer "B.Fab")
		)
		(fp_line
			(start 0.12065 -0.305054)
			(end 0.12065 -0.2794)
			(stroke
				(width 0.1)
				(type default)
			)
			(layer "B.Fab")
		)
		(fp_line
			(start -0.12065 -0.3048)
			(end -0.67945 -0.3048)
			(stroke
				(width 0.1)
				(type default)
			)
			(layer "B.Fab")
		)
		(fp_line
			(start -0.67945 -0.3048)
			(end -0.67945 0.3048)
			(stroke
				(width 0.1)
				(type default)
			)
			(layer "B.Fab")
		)
		(fp_line
			(start 0.12065 -0.2794)
			(end -0.12065 -0.2794)
			(stroke
				(width 0.1)
				(type default)
			)
			(layer "B.Fab")
		)
		(fp_line
			(start -0.12065 -0.2794)
			(end -0.12065 -0.3048)
			(stroke
				(width 0.1)
				(type default)
			)
			(layer "B.Fab")
		)
		(fp_line
			(start 0.12065 0.2794)
			(end 0.12065 0.3048)
			(stroke
				(width 0.1)
				(type default)
			)
			(layer "B.Fab")
		)
		(fp_line
			(start -0.120396 0.2794)
			(end 0.12065 0.2794)
			(stroke
				(width 0.1)
				(type default)
			)
			(layer "B.Fab")
		)
		(fp_line
			(start 0.67945 0.3048)
			(end 0.67945 -0.305054)
			(stroke
				(width 0.1)
				(type default)
			)
			(layer "B.Fab")
		)
		(fp_line
			(start 0.12065 0.3048)
			(end 0.67945 0.3048)
			(stroke
				(width 0.1)
				(type default)
			)
			(layer "B.Fab")
		)
		(fp_line
			(start -0.120396 0.3048)
			(end -0.120396 0.2794)
			(stroke
				(width 0.1)
				(type default)
			)
			(layer "B.Fab")
		)
		(fp_line
			(start -0.67945 0.3048)
			(end -0.120396 0.3048)
			(stroke
				(width 0.1)
				(type default)
			)
			(layer "B.Fab")
		)
		(pad "1" smd circle
			(at 0.40005 0 270)
			(size 0 0)
			(layers "B.Cu" "B.Mask" "B.Paste")
			(net "PVNN_TERM_CPU0")
		)
		(pad "2" smd circle
			(at -0.40005 0 270)
			(size 0 0)
			(layers "B.Cu" "B.Mask" "B.Paste")
			(net "DBP_CPU_HOOK8_MBP2_GTL_QS_N")
		)
	)
	(footprint ""
		(layer "B.Cu")
		(at 42.392346 -321.554856 -90)
		(property "Reference" "C57"
			(at 0 0 90)
			(layer "B.SilkS")
			(hide yes)
			(effects
				(font
					(size 1.27 1.27)
				)
				(justify mirror)
			)
		)
		(property "Value" ""
			(at 0 0 90)
			(layer "B.Fab")
			(effects
				(font
					(size 1.27 1.27)
				)
				(justify mirror)
			)
		)
		(duplicate_pad_numbers_are_jumpers no)
		(fp_line
			(start -1.524 0.762)
			(end 1.524 0.762)
			(stroke
				(width 0.1524)
				(type default)
			)
			(layer "B.SilkS")
		)
		(fp_line
			(start 1.524 0.762)
			(end 1.524 -0.762)
			(stroke
				(width 0.1524)
				(type default)
			)
			(layer "B.SilkS")
		)
		(fp_line
			(start -1.524 -0.762)
			(end -1.524 0.762)
			(stroke
				(width 0.1524)
				(type default)
			)
			(layer "B.SilkS")
		)
		(fp_line
			(start 1.524 -0.762)
			(end -1.524 -0.762)
			(stroke
				(width 0.1524)
				(type default)
			)
			(layer "B.SilkS")
		)
		(fp_line
			(start -1.1049 0.724916)
			(end -1.1049 -0.724916)
			(stroke
				(width 0.1)
				(type default)
			)
			(layer "B.Fab")
		)
		(fp_line
			(start 1.1049 0.724916)
			(end -1.1049 0.724916)
			(stroke
				(width 0.1)
				(type default)
			)
			(layer "B.Fab")
		)
		(fp_line
			(start -1.1049 -0.724916)
			(end 1.1049 -0.724916)
			(stroke
				(width 0.1)
				(type default)
			)
			(layer "B.Fab")
		)
		(fp_line
			(start 1.1049 -0.724916)
			(end 1.1049 0.724916)
			(stroke
				(width 0.1)
				(type default)
			)
			(layer "B.Fab")
		)
		(pad "1" smd rect
			(at 0.889 0 270)
			(size 1.016 1.27)
			(layers "B.Cu" "B.Mask" "B.Paste")
			(net "P12V_S3_AUX_CPU1_NVDIMM")
		)
		(pad "2" smd rect
			(at -0.889 0 270)
			(size 1.016 1.27)
			(layers "B.Cu" "B.Mask" "B.Paste")
			(net "GND")
		)
	)
	(footprint ""
		(layer "B.Cu")
		(at 359.250742 -210.19389)
		(property "Reference" "C507"
			(at 0 0 0)
			(layer "B.SilkS")
			(hide yes)
			(effects
				(font
					(size 1.27 1.27)
				)
				(justify mirror)
			)
		)
		(property "Value" ""
			(at 0 0 0)
			(layer "B.Fab")
			(effects
				(font
					(size 1.27 1.27)
				)
				(justify mirror)
			)
		)
		(duplicate_pad_numbers_are_jumpers no)
		(fp_line
			(start -1.524 -0.762)
			(end -1.524 0.762)
			(stroke
				(width 0.1524)
				(type default)
			)
			(layer "B.SilkS")
		)
		(fp_line
			(start -1.524 0.762)
			(end 1.524 0.762)
			(stroke
				(width 0.1524)
				(type default)
			)
			(layer "B.SilkS")
		)
		(fp_line
			(start 1.524 -0.762)
			(end -1.524 -0.762)
			(stroke
				(width 0.1524)
				(type default)
			)
			(layer "B.SilkS")
		)
		(fp_line
			(start 1.524 0.762)
			(end 1.524 -0.762)
			(stroke
				(width 0.1524)
				(type default)
			)
			(layer "B.SilkS")
		)
		(fp_line
			(start -1.1049 -0.724916)
			(end 1.1049 -0.724916)
			(stroke
				(width 0.1)
				(type default)
			)
			(layer "B.Fab")
		)
		(fp_line
			(start -1.1049 0.724916)
			(end -1.1049 -0.724916)
			(stroke
				(width 0.1)
				(type default)
			)
			(layer "B.Fab")
		)
		(fp_line
			(start 1.1049 -0.724916)
			(end 1.1049 0.724916)
			(stroke
				(width 0.1)
				(type default)
			)
			(layer "B.Fab")
		)
		(fp_line
			(start 1.1049 0.724916)
			(end -1.1049 0.724916)
			(stroke
				(width 0.1)
				(type default)
			)
			(layer "B.Fab")
		)
		(pad "1" smd rect
			(at 0.889 0)
			(size 1.016 1.27)
			(layers "B.Cu" "B.Mask" "B.Paste")
			(net "PVCCD_HV_CPU0")
		)
		(pad "2" smd rect
			(at -0.889 0)
			(size 1.016 1.27)
			(layers "B.Cu" "B.Mask" "B.Paste")
			(net "GND")
		)
	)
	(footprint ""
		(layer "B.Cu")
		(at 446.179956 -318.603376)
		(property "Reference" "R38"
			(at 0 0 0)
			(layer "B.SilkS")
			(hide yes)
			(effects
				(font
					(size 1.27 1.27)
				)
				(justify mirror)
			)
		)
		(property "Value" ""
			(at 0 0 0)
			(layer "B.Fab")
			(effects
				(font
					(size 1.27 1.27)
				)
				(justify mirror)
			)
		)
		(duplicate_pad_numbers_are_jumpers no)
		(fp_line
			(start -0.7874 -0.4064)
			(end -0.7874 0.4064)
			(stroke
				(width 0.1524)
				(type default)
			)
			(layer "B.SilkS")
		)
		(fp_line
			(start -0.7874 0.4064)
			(end 0.7874 0.4064)
			(stroke
				(width 0.1524)
				(type default)
			)
			(layer "B.SilkS")
		)
		(fp_line
			(start 0.7874 -0.4064)
			(end -0.7874 -0.4064)
			(stroke
				(width 0.1524)
				(type default)
			)
			(layer "B.SilkS")
		)
		(fp_line
			(start 0.7874 0.4064)
			(end 0.7874 -0.4064)
			(stroke
				(width 0.1524)
				(type default)
			)
			(layer "B.SilkS")
		)
		(fp_line
			(start -0.67945 -0.3048)
			(end -0.67945 0.3048)
			(stroke
				(width 0.1)
				(type default)
			)
			(layer "B.Fab")
		)
		(fp_line
			(start -0.67945 0.3048)
			(end -0.120396 0.3048)
			(stroke
				(width 0.1)
				(type default)
			)
			(layer "B.Fab")
		)
		(fp_line
			(start -0.12065 -0.3048)
			(end -0.67945 -0.3048)
			(stroke
				(width 0.1)
				(type default)
			)
			(layer "B.Fab")
		)
		(fp_line
			(start -0.12065 -0.2794)
			(end -0.12065 -0.3048)
			(stroke
				(width 0.1)
				(type default)
			)
			(layer "B.Fab")
		)
		(fp_line
			(start -0.120396 0.2794)
			(end 0.12065 0.2794)
			(stroke
				(width 0.1)
				(type default)
			)
			(layer "B.Fab")
		)
		(fp_line
			(start -0.120396 0.3048)
			(end -0.120396 0.2794)
			(stroke
				(width 0.1)
				(type default)
			)
			(layer "B.Fab")
		)
		(fp_line
			(start 0.12065 -0.305054)
			(end 0.12065 -0.2794)
			(stroke
				(width 0.1)
				(type default)
			)
			(layer "B.Fab")
		)
		(fp_line
			(start 0.12065 -0.2794)
			(end -0.12065 -0.2794)
			(stroke
				(width 0.1)
				(type default)
			)
			(layer "B.Fab")
		)
		(fp_line
			(start 0.12065 0.2794)
			(end 0.12065 0.3048)
			(stroke
				(width 0.1)
				(type default)
			)
			(layer "B.Fab")
		)
		(fp_line
			(start 0.12065 0.3048)
			(end 0.67945 0.3048)
			(stroke
				(width 0.1)
				(type default)
			)
			(layer "B.Fab")
		)
		(fp_line
			(start 0.67945 -0.305054)
			(end 0.12065 -0.305054)
			(stroke
				(width 0.1)
				(type default)
			)
			(layer "B.Fab")
		)
		(fp_line
			(start 0.67945 0.3048)
			(end 0.67945 -0.305054)
			(stroke
				(width 0.1)
				(type default)
			)
			(layer "B.Fab")
		)
		(pad "1" smd circle
			(at 0.40005 0 180)
			(size 0 0)
			(layers "B.Cu" "B.Mask" "B.Paste")
			(net "PD_CHG_CPU0_DIMM1_SAA")
		)
		(pad "2" smd circle
			(at -0.40005 0 180)
			(size 0 0)
			(layers "B.Cu" "B.Mask" "B.Paste")
			(net "GND")
		)
	)
	(footprint ""
		(layer "B.Cu")
		(at 323.646292 -190.269114 -90)
		(property "Reference" "R1"
			(at 0 0 90)
			(layer "B.SilkS")
			(hide yes)
			(effects
				(font
					(size 1.27 1.27)
				)
				(justify mirror)
			)
		)
		(property "Value" ""
			(at 0 0 90)
			(layer "B.Fab")
			(effects
				(font
					(size 1.27 1.27)
				)
				(justify mirror)
			)
		)
		(duplicate_pad_numbers_are_jumpers no)
		(fp_line
			(start -0.7874 0.4064)
			(end 0.7874 0.4064)
			(stroke
				(width 0.1524)
				(type default)
			)
			(layer "B.SilkS")
		)
		(fp_line
			(start 0.7874 0.4064)
			(end 0.7874 -0.4064)
			(stroke
				(width 0.1524)
				(type default)
			)
			(layer "B.SilkS")
		)
		(fp_line
			(start -0.7874 -0.4064)
			(end -0.7874 0.4064)
			(stroke
				(width 0.1524)
				(type default)
			)
			(layer "B.SilkS")
		)
		(fp_line
			(start 0.7874 -0.4064)
			(end -0.7874 -0.4064)
			(stroke
				(width 0.1524)
				(type default)
			)
			(layer "B.SilkS")
		)
		(fp_line
			(start -0.67945 0.3048)
			(end -0.120396 0.3048)
			(stroke
				(width 0.1)
				(type default)
			)
			(layer "B.Fab")
		)
		(fp_line
			(start -0.120396 0.3048)
			(end -0.120396 0.2794)
			(stroke
				(width 0.1)
				(type default)
			)
			(layer "B.Fab")
		)
		(fp_line
			(start 0.12065 0.3048)
			(end 0.67945 0.3048)
			(stroke
				(width 0.1)
				(type default)
			)
			(layer "B.Fab")
		)
		(fp_line
			(start 0.67945 0.3048)
			(end 0.67945 -0.305054)
			(stroke
				(width 0.1)
				(type default)
			)
			(layer "B.Fab")
		)
		(fp_line
			(start -0.120396 0.2794)
			(end 0.12065 0.2794)
			(stroke
				(width 0.1)
				(type default)
			)
			(layer "B.Fab")
		)
		(fp_line
			(start 0.12065 0.2794)
			(end 0.12065 0.3048)
			(stroke
				(width 0.1)
				(type default)
			)
			(layer "B.Fab")
		)
		(fp_line
			(start -0.12065 -0.2794)
			(end -0.12065 -0.3048)
			(stroke
				(width 0.1)
				(type default)
			)
			(layer "B.Fab")
		)
		(fp_line
			(start 0.12065 -0.2794)
			(end -0.12065 -0.2794)
			(stroke
				(width 0.1)
				(type default)
			)
			(layer "B.Fab")
		)
		(fp_line
			(start -0.67945 -0.3048)
			(end -0.67945 0.3048)
			(stroke
				(width 0.1)
				(type default)
			)
			(layer "B.Fab")
		)
		(fp_line
			(start -0.12065 -0.3048)
			(end -0.67945 -0.3048)
			(stroke
				(width 0.1)
				(type default)
			)
			(layer "B.Fab")
		)
		(fp_line
			(start 0.12065 -0.305054)
			(end 0.12065 -0.2794)
			(stroke
				(width 0.1)
				(type default)
			)
			(layer "B.Fab")
		)
		(fp_line
			(start 0.67945 -0.305054)
			(end 0.12065 -0.305054)
			(stroke
				(width 0.1)
				(type default)
			)
			(layer "B.Fab")
		)
		(pad "1" smd circle
			(at 0.40005 0 90)
			(size 0 0)
			(layers "B.Cu" "B.Mask" "B.Paste")
			(net "H_CPU_PRDY_QS_GTL_N")
		)
		(pad "2" smd circle
			(at -0.40005 0 90)
			(size 0 0)
			(layers "B.Cu" "B.Mask" "B.Paste")
			(net "H_CPU0_PRDY_QS_GTL_R_N")
		)
	)
)
